FILE_TYPE = MACRO_DRAWING;
SET COLOR_WIRE YELLOW;
SET COLOR_PROP ORANGE;
SET COLOR_DOT WHITE;
SET COLOR_ARC YELLOW;
SET COLOR_BODY GREEN;
SET COLOR_NOTE PURPLE;
SET PROP_DISPLAY VALUE;
SET PAGE_NUMBER P364;
FORCEADD UNIVERSAL_POWER..1
(-1800 3350);
FORCEPROP 3 LASTPIN (-1800 3300) SIG_NAME P3V3_AUX\g
J 0
(-1790 3310);
DISPLAY 0.659574 (-1790 3310);
PAINT MONO (-1790 3310);
DISPLAY INVISIBLE (-1790 3310);
FORCEPROP 1 LAST HDL_POWER P3V3_AUX
J 1
(-1800 3400);
DISPLAY 0.872340 (-1800 3400);
PAINT GREEN (-1800 3400);
FORCEPROP 2 LAST CDS_LIB pure_quanta_power
J 0
(-1800 3350);
PAINT MONO (-1800 3350);
DISPLAY INVISIBLE (-1800 3350);
FORCEPROP 1 LAST PATH I10
J 0
(-1750 3375);
DISPLAY 0.872340 (-1750 3375);
PAINT AQUA (-1750 3375);
DISPLAY INVISIBLE (-1750 3375);
FORCEADD UNIVERSAL_GND..1
(-150 1850);
FORCEPROP 3 LASTPIN (-150 1900) SIG_NAME GND\g
J 0
(-140 1910);
DISPLAY 0.659574 (-140 1910);
PAINT MONO (-140 1910);
DISPLAY INVISIBLE (-140 1910);
FORCEPROP 2 LAST CDS_LIB pure_quanta_power
J 0
(-150 1850);
DISPLAY INVISIBLE (-150 1850);
FORCEPROP 1 LAST HDL_POWER GND
J 1
(-125 1775);
DISPLAY 0.872340 (-125 1775);
PAINT GREEN (-125 1775);
DISPLAY INVISIBLE (-125 1775);
FORCEPROP 1 LAST PATH I12
J 0
(-75 1850);
DISPLAY 0.872340 (-75 1850);
PAINT AQUA (-75 1850);
DISPLAY INVISIBLE (-75 1850);
FORCEADD UNIVERSAL_GND..1
(925 2250);
FORCEPROP 3 LASTPIN (925 2300) SIG_NAME GND\g
J 0
(935 2310);
DISPLAY 0.659574 (935 2310);
PAINT MONO (935 2310);
DISPLAY INVISIBLE (935 2310);
FORCEPROP 2 LAST CDS_LIB pure_quanta_power
J 0
(925 2250);
PAINT MONO (925 2250);
DISPLAY INVISIBLE (925 2250);
FORCEPROP 1 LAST HDL_POWER GND
J 1
(950 2175);
DISPLAY 0.872340 (950 2175);
PAINT GREEN (950 2175);
DISPLAY INVISIBLE (950 2175);
FORCEPROP 1 LAST PATH I13
J 0
(1000 2250);
DISPLAY 0.872340 (1000 2250);
PAINT AQUA (1000 2250);
DISPLAY INVISIBLE (1000 2250);
FORCEADD Q_CAP..1
(925 2475);
FORCEPROP 1 LAST LOCATION C1775
J 0
(975 2575);
DISPLAY 0.787234 (975 2575);
FORCEPROP 2 LAST $SEC 1
J 0
(975 2675);
DISPLAY 0.680851 (975 2675);
PAINT MONO (975 2675);
DISPLAY INVISIBLE (975 2675);
FORCEPROP 2 LAST CDS_SEC 1
J 0
(975 2675);
DISPLAY 1.021277 (975 2675);
DISPLAY INVISIBLE (975 2675);
FORCEPROP 1 LASTPIN (925 2575) $PN 1
J 0
(935 2555);
DISPLAY 0.787234 (935 2555);
FORCEPROP 1 LASTPIN (925 2375) $PN 2
J 0
(935 2355);
DISPLAY 0.787234 (935 2355);
FORCEPROP 1 LAST PACK_TYPE 0402
J 0
(975 2275);
DISPLAY 0.510638 (975 2275);
FORCEPROP 1 LAST VALUE 0.1UF
J 0
(975 2525);
DISPLAY 0.510638 (975 2525);
FORCEPROP 1 LAST MATERIAL X7R
J 0
(975 2375);
DISPLAY 0.510638 (975 2375);
FORCEPROP 1 LAST VOLTAGE 25V
J 0
(975 2475);
DISPLAY 0.510638 (975 2475);
FORCEPROP 1 LAST TOLERANCE 10%
J 0
(975 2425);
DISPLAY 0.510638 (975 2425);
FORCEPROP 2 LAST CDS_LIB pure_quanta
J 2
(925 2475);
PAINT MONO (925 2475);
DISPLAY INVISIBLE (925 2475);
FORCEPROP 1 LAST PATH I14
J 0
(975 2625);
DISPLAY 0.978723 (975 2625);
PAINT WHITE (975 2625);
DISPLAY INVISIBLE (975 2625);
FORCEPROP 1 LAST PART_NUMBER CH4104K1B00
J 0
(975 2325);
DISPLAY 0.510638 (975 2325);
DISPLAY INVISIBLE (975 2325);
FORCEADD UNIVERSAL_POWER..1
(925 2800);
FORCEPROP 3 LASTPIN (925 2750) SIG_NAME P3V3_AUX\g
J 0
(935 2760);
DISPLAY 0.659574 (935 2760);
PAINT MONO (935 2760);
DISPLAY INVISIBLE (935 2760);
FORCEPROP 1 LAST HDL_POWER P3V3_AUX
J 1
(925 2850);
DISPLAY 0.872340 (925 2850);
PAINT GREEN (925 2850);
FORCEPROP 2 LAST CDS_LIB pure_quanta_power
J 0
(925 2800);
PAINT MONO (925 2800);
DISPLAY INVISIBLE (925 2800);
FORCEPROP 1 LAST PATH I15
J 0
(975 2825);
DISPLAY 0.872340 (975 2825);
PAINT AQUA (975 2825);
DISPLAY INVISIBLE (975 2825);
FORCEADD UNIVERSAL_GND..1
(1750 1550);
FORCEPROP 3 LASTPIN (1750 1600) SIG_NAME GND\g
J 0
(1760 1610);
DISPLAY 0.659574 (1760 1610);
PAINT MONO (1760 1610);
DISPLAY INVISIBLE (1760 1610);
FORCEPROP 2 LAST CDS_LIB pure_quanta_power
J 0
(1750 1550);
DISPLAY INVISIBLE (1750 1550);
FORCEPROP 1 LAST HDL_POWER GND
J 1
(1775 1475);
DISPLAY 0.872340 (1775 1475);
PAINT GREEN (1775 1475);
DISPLAY INVISIBLE (1775 1475);
FORCEPROP 1 LAST PATH I22
J 0
(1825 1550);
DISPLAY 0.872340 (1825 1550);
PAINT AQUA (1825 1550);
DISPLAY INVISIBLE (1825 1550);
FORCEADD Q_RES..1
(2000 2075);
FORCEPROP 1 LAST LOCATION R2944
J 0
(1800 2075);
DISPLAY 0.723404 (1800 2075);
FORCEPROP 2 LAST $SEC 1
J 0
(1950 2275);
DISPLAY 0.680851 (1950 2275);
PAINT MONO (1950 2275);
DISPLAY INVISIBLE (1950 2275);
FORCEPROP 0 LAST CDS_SEC 1
J 0
(1700 2150);
DISPLAY INVISIBLE (1700 2150);
FORCEPROP 1 LASTPIN (1900 2075) $PN 1
J 0
(1912 2087);
DISPLAY 0.723404 (1912 2087);
PAINT MONO (1912 2087);
FORCEPROP 1 LASTPIN (2100 2075) $PN 2
J 0
(2062 2087);
DISPLAY 0.723404 (2062 2087);
PAINT MONO (2062 2087);
FORCEPROP 1 LAST VALUE 33.2
J 2
(2250 2075);
DISPLAY 0.723404 (2250 2075);
FORCEPROP 1 LAST MATERIAL CHIP
J 0
(2025 2025);
DISPLAY 0.723404 (2025 2025);
FORCEPROP 1 LAST PACK_TYPE 0402LF
J 0
(1825 2025);
DISPLAY 0.723404 (1825 2025);
FORCEPROP 1 LAST WATTAGE 1/16W
J 2
(2400 2025);
DISPLAY 0.723404 (2400 2025);
PAINT SKYBLUE (2400 2025);
DISPLAY INVISIBLE (2400 2025);
FORCEPROP 1 LAST TOLERANCE 1%
J 0
(2475 2075);
DISPLAY 0.723404 (2475 2075);
PAINT SKYBLUE (2475 2075);
DISPLAY INVISIBLE (2475 2075);
FORCEPROP 2 LAST CDS_LIB pure_quanta
J 0
(2000 2075);
DISPLAY INVISIBLE (2000 2075);
FORCEPROP 1 LAST PATH I24
J 0
(1950 2225);
DISPLAY 0.978723 (1950 2225);
PAINT WHITE (1950 2225);
DISPLAY INVISIBLE (1950 2225);
FORCEPROP 1 LAST PART_NUMBER CS03322FB03
J 0
(1600 1975);
DISPLAY 0.723404 (1600 1975);
PAINT WHITE (1600 1975);
DISPLAY INVISIBLE (1600 1975);
FORCEADD Q_RES..2
(1725 2325);
FORCEPROP 1 LAST LOCATION R2946
J 0
(1770 2450);
DISPLAY 0.638298 (1770 2450);
FORCEPROP 2 LAST $SEC 1
J 0
(1775 2550);
DISPLAY 0.680851 (1775 2550);
PAINT MONO (1775 2550);
DISPLAY INVISIBLE (1775 2550);
FORCEPROP 2 LAST CDS_SEC 1
J 0
(1775 2550);
DISPLAY 1.021277 (1775 2550);
DISPLAY INVISIBLE (1775 2550);
FORCEPROP 1 LASTPIN (1725 2425) $PN 1
J 0
(1730 2387);
DISPLAY 0.787234 (1730 2387);
FORCEPROP 1 LASTPIN (1725 2225) $PN 2
J 0
(1730 2235);
DISPLAY 0.787234 (1730 2235);
FORCEPROP 1 LAST PACK_TYPE 0402LF
J 0
(1765 2200);
DISPLAY 0.638298 (1765 2200);
FORCEPROP 1 LAST MATERIAL EMPTY
J 0
(1765 2250);
DISPLAY 0.638298 (1765 2250);
PAINT RED (1765 2250);
FORCEPROP 1 LAST WATTAGE 1/16W
J 0
(1765 2300);
DISPLAY 0.638298 (1765 2300);
FORCEPROP 1 LAST TOLERANCE 5%
J 0
(1770 2350);
DISPLAY 0.638298 (1770 2350);
FORCEPROP 1 LAST VALUE 4.7K
J 0
(1770 2400);
DISPLAY 0.638298 (1770 2400);
FORCEPROP 2 LAST CDS_LIB pure_quanta
J 0
(1725 2325);
PAINT MONO (1725 2325);
DISPLAY INVISIBLE (1725 2325);
FORCEPROP 1 LAST PATH I25
J 0
(1775 2500);
DISPLAY 0.978723 (1775 2500);
PAINT WHITE (1775 2500);
DISPLAY INVISIBLE (1775 2500);
FORCEPROP 1 LAST PART_NUMBER CS24702JB10
J 0
(1765 2150);
DISPLAY 0.638298 (1765 2150);
DISPLAY INVISIBLE (1765 2150);
FORCEADD UNIVERSAL_POWER..1
(1725 2575);
FORCEPROP 3 LASTPIN (1725 2525) SIG_NAME P3V3_AUX\g
J 0
(1735 2535);
DISPLAY 0.659574 (1735 2535);
PAINT MONO (1735 2535);
DISPLAY INVISIBLE (1735 2535);
FORCEPROP 1 LAST HDL_POWER P3V3_AUX
J 1
(1725 2625);
DISPLAY 0.872340 (1725 2625);
PAINT GREEN (1725 2625);
FORCEPROP 2 LAST CDS_LIB pure_quanta_power
J 0
(1725 2575);
PAINT MONO (1725 2575);
DISPLAY INVISIBLE (1725 2575);
FORCEPROP 1 LAST PATH I26
J 0
(1775 2600);
DISPLAY 0.872340 (1775 2600);
PAINT AQUA (1775 2600);
DISPLAY INVISIBLE (1775 2600);
FORCEADD OFFPAGE..2
(3275 2075);
FORCEPROP 2 LAST $XR0 241 
J 0
(3464 2075);
DISPLAY 0.638298 (3464 2075);
PAINT MONO (3464 2075);
FORCEPROP 2 LAST CDS_LIB standard
J 0
(3275 2075);
DISPLAY INVISIBLE (3275 2075);
FORCEPROP 1 LAST OFFPAGE TRUE
J 0
(3600 1950);
DISPLAY 0.872340 (3600 1950);
PAINT AQUA (3600 1950);
DISPLAY INVISIBLE (3600 1950);
FORCEPROP 1 LAST COMMENT_BODY TRUE
J 0
(3230 1980);
DISPLAY 0.872340 (3230 1980);
PAINT GREEN (3230 1980);
DISPLAY INVISIBLE (3230 1980);
FORCEPROP 2 LAST PATH I27
J 0
(3475 2125);
DISPLAY 1.021277 (3475 2125);
DISPLAY INVISIBLE (3475 2125);
FORCEADD Q_RES..2
(-1800 3100);
FORCEPROP 1 LAST LOCATION R2940
J 0
(-1755 3225);
DISPLAY 0.638298 (-1755 3225);
FORCEPROP 2 LAST $SEC 1
J 0
(-1750 3325);
DISPLAY 0.680851 (-1750 3325);
PAINT MONO (-1750 3325);
DISPLAY INVISIBLE (-1750 3325);
FORCEPROP 2 LAST CDS_SEC 1
J 0
(-1750 3325);
DISPLAY 1.021277 (-1750 3325);
DISPLAY INVISIBLE (-1750 3325);
FORCEPROP 1 LASTPIN (-1800 3200) $PN 1
J 0
(-1795 3162);
DISPLAY 0.787234 (-1795 3162);
FORCEPROP 1 LASTPIN (-1800 3000) $PN 2
J 0
(-1795 3010);
DISPLAY 0.787234 (-1795 3010);
FORCEPROP 1 LAST WATTAGE 1/16W
J 0
(-1760 3075);
DISPLAY 0.638298 (-1760 3075);
FORCEPROP 1 LAST MATERIAL EMPTY
J 0
(-1760 3025);
DISPLAY 0.638298 (-1760 3025);
PAINT RED (-1760 3025);
FORCEPROP 1 LAST PACK_TYPE 0402LF
J 0
(-1760 2975);
DISPLAY 0.638298 (-1760 2975);
FORCEPROP 1 LAST TOLERANCE 5%
J 0
(-1755 3125);
DISPLAY 0.638298 (-1755 3125);
FORCEPROP 1 LAST VALUE 4.7K
J 0
(-1755 3175);
DISPLAY 0.638298 (-1755 3175);
FORCEPROP 2 LAST CDS_LIB pure_quanta
J 0
(-1800 3100);
PAINT MONO (-1800 3100);
DISPLAY INVISIBLE (-1800 3100);
FORCEPROP 1 LAST PATH I28
J 0
(-1750 3275);
DISPLAY 0.978723 (-1750 3275);
PAINT WHITE (-1750 3275);
DISPLAY INVISIBLE (-1750 3275);
FORCEPROP 1 LAST PART_NUMBER CS24702JB10
J 0
(-1760 2925);
DISPLAY 0.638298 (-1760 2925);
DISPLAY INVISIBLE (-1760 2925);
FORCEADD Q_RES..2
(-1775 2625);
FORCEPROP 1 LAST LOCATION R2941
J 0
(-1730 2750);
DISPLAY 0.978723 (-1730 2750);
FORCEPROP 0 LAST $SEC 1
J 0
(-1725 2800);
DISPLAY 0.680851 (-1725 2800);
PAINT MONO (-1725 2800);
DISPLAY INVISIBLE (-1725 2800);
FORCEPROP 0 LAST CDS_SEC 1
J 0
(-1725 2800);
DISPLAY 1.021277 (-1725 2800);
DISPLAY INVISIBLE (-1725 2800);
FORCEPROP 1 LASTPIN (-1775 2725) $PN 1
J 0
(-1770 2687);
DISPLAY 0.787234 (-1770 2687);
PAINT MONO (-1770 2687);
FORCEPROP 1 LASTPIN (-1775 2525) $PN 2
J 0
(-1770 2535);
DISPLAY 0.787234 (-1770 2535);
PAINT MONO (-1770 2535);
FORCEPROP 1 LAST VALUE 100K
J 0
(-1730 2700);
DISPLAY 0.510638 (-1730 2700);
FORCEPROP 1 LAST MATERIAL CHIP
J 0
(-1735 2550);
DISPLAY 0.510638 (-1735 2550);
FORCEPROP 1 LAST WATTAGE 1/16W
J 0
(-1735 2600);
DISPLAY 0.510638 (-1735 2600);
FORCEPROP 1 LAST TOLERANCE 1%
J 0
(-1730 2650);
DISPLAY 0.510638 (-1730 2650);
FORCEPROP 1 LAST PACK_TYPE 0402LF
J 0
(-1735 2450);
DISPLAY 0.510638 (-1735 2450);
FORCEPROP 2 LAST CDS_LIB pure_quanta
J 0
(-1775 2625);
DISPLAY INVISIBLE (-1775 2625);
FORCEPROP 1 LAST PATH I29
J 0
(-1725 2800);
DISPLAY 0.978723 (-1725 2800);
PAINT WHITE (-1725 2800);
DISPLAY INVISIBLE (-1725 2800);
FORCEPROP 1 LAST PART_NUMBER CS41002FB09
J 0
(-1735 2500);
DISPLAY 0.510638 (-1735 2500);
DISPLAY INVISIBLE (-1735 2500);
FORCEADD Q_RES..2
(1750 1775);
FORCEPROP 1 LAST LOCATION R2948
J 0
(1795 1900);
DISPLAY 0.978723 (1795 1900);
FORCEPROP 0 LAST $SEC 1
J 0
(1800 1950);
DISPLAY 0.680851 (1800 1950);
PAINT MONO (1800 1950);
DISPLAY INVISIBLE (1800 1950);
FORCEPROP 0 LAST CDS_SEC 1
J 0
(1800 1950);
DISPLAY 1.021277 (1800 1950);
DISPLAY INVISIBLE (1800 1950);
FORCEPROP 1 LASTPIN (1750 1875) $PN 1
J 0
(1755 1837);
DISPLAY 0.787234 (1755 1837);
PAINT MONO (1755 1837);
FORCEPROP 1 LASTPIN (1750 1675) $PN 2
J 0
(1755 1685);
DISPLAY 0.787234 (1755 1685);
PAINT MONO (1755 1685);
FORCEPROP 1 LAST VALUE 4.7K
J 0
(1795 1850);
DISPLAY 0.638298 (1795 1850);
FORCEPROP 1 LAST PACK_TYPE 0402LF
J 0
(1790 1650);
DISPLAY 0.638298 (1790 1650);
FORCEPROP 1 LAST TOLERANCE 5%
J 0
(1795 1800);
DISPLAY 0.638298 (1795 1800);
FORCEPROP 1 LAST MATERIAL EMPTY
J 0
(1790 1700);
DISPLAY 0.638298 (1790 1700);
PAINT RED (1790 1700);
FORCEPROP 1 LAST WATTAGE 1/16W
J 0
(1790 1750);
DISPLAY 0.638298 (1790 1750);
FORCEPROP 2 LAST CDS_LIB pure_quanta
J 0
(1750 1775);
DISPLAY INVISIBLE (1750 1775);
FORCEPROP 1 LAST PATH I30
J 0
(1800 1950);
DISPLAY 0.978723 (1800 1950);
PAINT WHITE (1800 1950);
DISPLAY INVISIBLE (1800 1950);
FORCEPROP 1 LAST PART_NUMBER CS24702JB10
J 0
(1790 1600);
DISPLAY 0.638298 (1790 1600);
DISPLAY INVISIBLE (1790 1600);
FORCEADD 74LVC1G08W57..1
(250 2125);
FORCEPROP 1 LAST LOCATION U278
J 0
(106 2556);
DISPLAY 0.723404 (106 2556);
PAINT GREEN (106 2556);
FORCEPROP 0 LAST $SEC 1
J 0
(125 2600);
DISPLAY 0.680851 (125 2600);
PAINT MONO (125 2600);
DISPLAY INVISIBLE (125 2600);
FORCEPROP 0 LAST CDS_SEC 1
J 0
(125 2600);
DISPLAY 1.021277 (125 2600);
DISPLAY INVISIBLE (125 2600);
FORCEPROP 0 LASTPIN (-50 2225) $PN 1
J 2
(-60 2235);
DISPLAY 0.680851 (-60 2235);
PAINT MONO (-60 2235);
FORCEPROP 0 LASTPIN (-50 2125) $PN 2
J 2
(-60 2135);
DISPLAY 0.680851 (-60 2135);
PAINT MONO (-60 2135);
FORCEPROP 0 LASTPIN (-50 2025) $PN 3
J 2
(-60 2035);
DISPLAY 0.680851 (-60 2035);
PAINT MONO (-60 2035);
FORCEPROP 0 LASTPIN (550 2225) $PN 5
J 0
(560 2235);
DISPLAY 0.680851 (560 2235);
PAINT MONO (560 2235);
FORCEPROP 0 LASTPIN (550 2075) $PN 4
J 0
(560 2085);
DISPLAY 0.680851 (560 2085);
PAINT MONO (560 2085);
FORCEPROP 1 LAST MATERIAL IC
J 0
(106 2282);
DISPLAY 0.723404 (106 2282);
PAINT GREEN (106 2282);
FORCEPROP 2 LAST VALUE 74LVC1G08W5-7
J 0
(100 2400);
DISPLAY 0.808511 (100 2400);
FORCEPROP 2 LAST PART_TYPE SMLF
J 0
(100 2450);
DISPLAY 0.808511 (100 2450);
FORCEPROP 1 LAST NEEDS_NO_SIZE TRUE
J 0
(250 2125);
DISPLAY 0.723404 (250 2125);
PAINT GREEN (250 2125);
DISPLAY INVISIBLE (250 2125);
FORCEPROP 1 LAST CDS_LMAN_SYM_OUTLINE -150,150,150,-150
J 0
(250 2125);
DISPLAY 0.468085 (250 2125);
PAINT GREEN (250 2125);
DISPLAY INVISIBLE (250 2125);
FORCEPROP 2 LAST CDS_LIB pure_quanta
J 0
(250 2125);
DISPLAY INVISIBLE (250 2125);
FORCEPROP 1 LAST PATH I31
J 0
(250 2125);
DISPLAY 0.723404 (250 2125);
PAINT GREEN (250 2125);
DISPLAY INVISIBLE (250 2125);
FORCEPROP 1 LAST PART_NUMBER AL1G0008020
J 0
(100 2350);
DISPLAY 0.723404 (100 2350);
PAINT GREEN (100 2350);
DISPLAY INVISIBLE (100 2350);
FORCEADD Q_RES..1
(-1325 2125);
FORCEPROP 1 LAST LOCATION R3770
J 0
(-1550 2125);
DISPLAY 0.638298 (-1550 2125);
FORCEPROP 0 LAST $SEC 1
J 0
(-1025 2200);
DISPLAY 0.680851 (-1025 2200);
PAINT MONO (-1025 2200);
DISPLAY INVISIBLE (-1025 2200);
FORCEPROP 0 LAST CDS_SEC 1
J 0
(-1025 2200);
DISPLAY 1.021277 (-1025 2200);
DISPLAY INVISIBLE (-1025 2200);
FORCEPROP 1 LASTPIN (-1425 2125) $PN 1
J 0
(-1413 2137);
DISPLAY 0.787234 (-1413 2137);
PAINT MONO (-1413 2137);
FORCEPROP 1 LASTPIN (-1225 2125) $PN 2
J 0
(-1263 2137);
DISPLAY 0.787234 (-1263 2137);
PAINT MONO (-1263 2137);
FORCEPROP 1 LAST PACK_TYPE 0402LF
J 0
(-1200 2175);
DISPLAY 0.319149 (-1200 2175);
FORCEPROP 1 LAST VALUE 0
J 2
(-1175 2125);
DISPLAY 0.404255 (-1175 2125);
FORCEPROP 1 LAST TOLERANCE 5%
J 0
(-1150 2125);
DISPLAY 0.404255 (-1150 2125);
FORCEPROP 1 LAST MATERIAL CHIP
J 0
(-1075 2125);
DISPLAY 0.404255 (-1075 2125);
FORCEPROP 1 LAST WATTAGE 1/16W
J 2
(-1025 2175);
DISPLAY 0.319149 (-1025 2175);
FORCEPROP 2 LAST CDS_LIB pure_quanta
J 0
(-1325 2125);
DISPLAY INVISIBLE (-1325 2125);
FORCEPROP 1 LAST PATH I34
J 0
(-1375 2275);
DISPLAY 0.978723 (-1375 2275);
PAINT WHITE (-1375 2275);
DISPLAY INVISIBLE (-1375 2275);
FORCEPROP 1 LAST PART_NUMBER CS00002JB13
J 0
(-1200 2150);
DISPLAY 0.319149 (-1200 2150);
DISPLAY INVISIBLE (-1200 2150);
FORCEADD OFFPAGE..4
R 2
(-2025 2125);
FORCEPROP 2 LAST $XR0 126 
J 0
(-2277 2125);
DISPLAY 0.638298 (-2277 2125);
PAINT MONO (-2277 2125);
FORCEPROP 2 LAST CDS_LIB standard
J 0
(-2025 2125);
DISPLAY INVISIBLE (-2025 2125);
FORCEPROP 1 LAST OFFPAGE TRUE
J 2
(-2350 2000);
DISPLAY 0.872340 (-2350 2000);
PAINT GREEN (-2350 2000);
DISPLAY INVISIBLE (-2350 2000);
FORCEPROP 1 LAST COMMENT_BODY TRUE
J 2
(-2000 2025);
DISPLAY 0.872340 (-2000 2025);
PAINT GREEN (-2000 2025);
DISPLAY INVISIBLE (-2000 2025);
FORCEPROP 2 LAST PATH I35
J 0
(-1975 2200);
DISPLAY 1.021277 (-1975 2200);
DISPLAY INVISIBLE (-1975 2200);
FORCEADD UNIVERSAL_GND..1
(-25 75);
FORCEPROP 3 LASTPIN (-25 125) SIG_NAME GND\g
J 0
(-15 135);
DISPLAY 0.659574 (-15 135);
PAINT MONO (-15 135);
DISPLAY INVISIBLE (-15 135);
FORCEPROP 2 LAST CDS_LIB pure_quanta_power
J 0
(-25 75);
DISPLAY INVISIBLE (-25 75);
FORCEPROP 1 LAST HDL_POWER GND
J 1
(0 0);
DISPLAY 0.872340 (0 0);
PAINT GREEN (0 0);
DISPLAY INVISIBLE (0 0);
FORCEPROP 1 LAST PATH I36
J 0
(50 75);
DISPLAY 0.872340 (50 75);
PAINT AQUA (50 75);
DISPLAY INVISIBLE (50 75);
FORCEADD 74LVC2G07DW7..1
(550 225);
FORCEPROP 1 LAST LOCATION U308
J 0
(381 606);
DISPLAY 0.723404 (381 606);
PAINT GREEN (381 606);
FORCEPROP 0 LAST $SEC 1
J 0
(400 750);
DISPLAY 0.680851 (400 750);
PAINT MONO (400 750);
DISPLAY INVISIBLE (400 750);
FORCEPROP 0 LAST CDS_SEC 1
J 0
(400 750);
DISPLAY 1.021277 (400 750);
DISPLAY INVISIBLE (400 750);
FORCEPROP 0 LASTPIN (225 275) $PN 1
J 2
(215 285);
DISPLAY 0.680851 (215 285);
PAINT MONO (215 285);
FORCEPROP 0 LASTPIN (875 275) $PN 6
J 0
(885 285);
DISPLAY 0.680851 (885 285);
PAINT MONO (885 285);
FORCEPROP 0 LASTPIN (225 175) $PN 3
J 2
(215 185);
DISPLAY 0.680851 (215 185);
PAINT MONO (215 185);
FORCEPROP 0 LASTPIN (875 175) $PN 4
J 0
(885 185);
DISPLAY 0.680851 (885 185);
PAINT MONO (885 185);
FORCEPROP 0 LASTPIN (225 225) $PN 2
J 2
(215 235);
DISPLAY 0.680851 (215 235);
PAINT MONO (215 235);
FORCEPROP 0 LASTPIN (875 225) $PN 5
J 0
(885 235);
DISPLAY 0.680851 (885 235);
PAINT MONO (885 235);
FORCEPROP 1 LAST MATERIAL IC
J 0
(381 332);
DISPLAY 0.723404 (381 332);
PAINT GREEN (381 332);
FORCEPROP 2 LAST PART_TYPE SMLF
J 0
(400 700);
DISPLAY 1.021277 (400 700);
FORCEPROP 2 LAST VALUE 74LVC2G07DW-7
J 0
(250 525);
DISPLAY 1.021277 (250 525);
FORCEPROP 1 LAST CDS_LMAN_SYM_OUTLINE -175,100,175,-100
J 0
(550 225);
DISPLAY 0.468085 (550 225);
PAINT GREEN (550 225);
DISPLAY INVISIBLE (550 225);
FORCEPROP 1 LAST NEEDS_NO_SIZE TRUE
J 0
(550 225);
DISPLAY 0.723404 (550 225);
PAINT GREEN (550 225);
DISPLAY INVISIBLE (550 225);
FORCEPROP 2 LAST CDS_LIB pure_quanta
J 0
(550 225);
DISPLAY INVISIBLE (550 225);
FORCEPROP 1 LAST PATH I37
J 0
(550 225);
DISPLAY 0.723404 (550 225);
PAINT GREEN (550 225);
DISPLAY INVISIBLE (550 225);
FORCEPROP 1 LAST PART_NUMBER AL002G07003
J 0
(381 459);
DISPLAY 0.723404 (381 459);
PAINT GREEN (381 459);
DISPLAY INVISIBLE (381 459);
FORCEADD UNIVERSAL_POWER..1
(1250 -25);
FORCEPROP 3 LASTPIN (1250 -75) SIG_NAME P3V3_AUX\g
J 0
(1260 -65);
DISPLAY 0.659574 (1260 -65);
PAINT MONO (1260 -65);
DISPLAY INVISIBLE (1260 -65);
FORCEPROP 1 LAST HDL_POWER P3V3_AUX
J 1
(1250 25);
DISPLAY 0.872340 (1250 25);
PAINT GREEN (1250 25);
FORCEPROP 2 LAST CDS_LIB pure_quanta_power
J 0
(1250 -25);
PAINT MONO (1250 -25);
DISPLAY INVISIBLE (1250 -25);
FORCEPROP 1 LAST PATH I38
J 0
(1300 0);
DISPLAY 0.872340 (1300 0);
PAINT AQUA (1300 0);
DISPLAY INVISIBLE (1300 0);
FORCEADD UNIVERSAL_GND..1
(1250 -575);
FORCEPROP 3 LASTPIN (1250 -525) SIG_NAME GND\g
J 0
(1260 -515);
DISPLAY 0.659574 (1260 -515);
PAINT MONO (1260 -515);
DISPLAY INVISIBLE (1260 -515);
FORCEPROP 2 LAST CDS_LIB pure_quanta_power
J 0
(1250 -575);
PAINT MONO (1250 -575);
DISPLAY INVISIBLE (1250 -575);
FORCEPROP 1 LAST HDL_POWER GND
J 1
(1275 -650);
DISPLAY 0.872340 (1275 -650);
PAINT GREEN (1275 -650);
DISPLAY INVISIBLE (1275 -650);
FORCEPROP 1 LAST PATH I39
J 0
(1325 -575);
DISPLAY 0.872340 (1325 -575);
PAINT AQUA (1325 -575);
DISPLAY INVISIBLE (1325 -575);
FORCEADD Q_CAP..1
(1250 -350);
FORCEPROP 1 LAST LOCATION C69
J 0
(1300 -250);
DISPLAY 0.787234 (1300 -250);
FORCEPROP 2 LAST $SEC 1
J 0
(1300 -150);
DISPLAY 0.680851 (1300 -150);
PAINT MONO (1300 -150);
DISPLAY INVISIBLE (1300 -150);
FORCEPROP 2 LAST CDS_SEC 1
J 0
(1300 -150);
DISPLAY 1.021277 (1300 -150);
DISPLAY INVISIBLE (1300 -150);
FORCEPROP 1 LASTPIN (1250 -250) $PN 1
J 0
(1260 -270);
DISPLAY 0.787234 (1260 -270);
FORCEPROP 1 LASTPIN (1250 -450) $PN 2
J 0
(1260 -470);
DISPLAY 0.787234 (1260 -470);
FORCEPROP 1 LAST MATERIAL X7R
J 0
(1300 -450);
DISPLAY 0.510638 (1300 -450);
FORCEPROP 1 LAST TOLERANCE 10%
J 0
(1300 -400);
DISPLAY 0.510638 (1300 -400);
FORCEPROP 1 LAST VOLTAGE 25V
J 0
(1300 -350);
DISPLAY 0.510638 (1300 -350);
FORCEPROP 1 LAST PACK_TYPE 0402
J 0
(1300 -550);
DISPLAY 0.510638 (1300 -550);
FORCEPROP 1 LAST VALUE 0.1UF
J 0
(1300 -300);
DISPLAY 0.510638 (1300 -300);
FORCEPROP 2 LAST CDS_LIB pure_quanta
J 2
(1250 -350);
PAINT MONO (1250 -350);
DISPLAY INVISIBLE (1250 -350);
FORCEPROP 1 LAST PATH I40
J 0
(1300 -200);
DISPLAY 0.978723 (1300 -200);
PAINT WHITE (1300 -200);
DISPLAY INVISIBLE (1300 -200);
FORCEPROP 1 LAST PART_NUMBER CH4104K1B00
J 0
(1300 -500);
DISPLAY 0.510638 (1300 -500);
DISPLAY INVISIBLE (1300 -500);
FORCEADD Q_RES..1
(-1125 275);
FORCEPROP 1 LAST LOCATION R4268
J 0
(-1175 325);
DISPLAY 0.978723 (-1175 325);
FORCEPROP 0 LAST $SEC 1
J 0
(-1175 375);
DISPLAY 0.680851 (-1175 375);
PAINT MONO (-1175 375);
DISPLAY INVISIBLE (-1175 375);
FORCEPROP 0 LAST CDS_SEC 1
J 0
(-1175 375);
DISPLAY 1.021277 (-1175 375);
DISPLAY INVISIBLE (-1175 375);
FORCEPROP 1 LASTPIN (-1225 275) $PN 1
J 0
(-1213 287);
DISPLAY 0.787234 (-1213 287);
PAINT MONO (-1213 287);
FORCEPROP 1 LASTPIN (-1025 275) $PN 2
J 0
(-1063 287);
DISPLAY 0.787234 (-1063 287);
PAINT MONO (-1063 287);
FORCEPROP 1 LAST TOLERANCE 5%
J 0
(-950 275);
DISPLAY 0.404255 (-950 275);
FORCEPROP 1 LAST MATERIAL CHIP
J 0
(-875 275);
DISPLAY 0.404255 (-875 275);
FORCEPROP 1 LAST WATTAGE 1/16W
J 2
(-825 325);
DISPLAY 0.319149 (-825 325);
FORCEPROP 1 LAST PACK_TYPE 0402LF
J 0
(-1000 325);
DISPLAY 0.319149 (-1000 325);
FORCEPROP 1 LAST VALUE 0
J 2
(-975 275);
DISPLAY 0.404255 (-975 275);
FORCEPROP 2 LAST CDS_LIB pure_quanta
J 0
(-1125 275);
DISPLAY INVISIBLE (-1125 275);
FORCEPROP 1 LAST PATH I41
J 0
(-1175 425);
DISPLAY 0.978723 (-1175 425);
PAINT WHITE (-1175 425);
DISPLAY INVISIBLE (-1175 425);
FORCEPROP 1 LAST PART_NUMBER CS00002JB13
J 0
(-1000 300);
DISPLAY 0.319149 (-1000 300);
DISPLAY INVISIBLE (-1000 300);
FORCEADD OFFPAGE..4
R 2
(-2175 275);
FORCEPROP 2 LAST $XR0 85 
J 0
(-2426 275);
DISPLAY 0.638298 (-2426 275);
PAINT MONO (-2426 275);
FORCEPROP 1 LAST OFFPAGE TRUE
J 2
(-2500 150);
DISPLAY 0.872340 (-2500 150);
PAINT GREEN (-2500 150);
DISPLAY INVISIBLE (-2500 150);
FORCEPROP 2 LAST PATH I42
J 0
(-2125 350);
DISPLAY 1.021277 (-2125 350);
DISPLAY INVISIBLE (-2125 350);
FORCEPROP 1 LAST COMMENT_BODY TRUE
J 2
(-2150 175);
DISPLAY 0.872340 (-2150 175);
PAINT GREEN (-2150 175);
DISPLAY INVISIBLE (-2150 175);
FORCEPROP 2 LAST CDS_LIB standard
J 0
(-2175 275);
DISPLAY INVISIBLE (-2175 275);
FORCEADD Q_RES..2
(2175 -25);
FORCEPROP 1 LAST LOCATION R4265
J 0
(2220 100);
DISPLAY 0.978723 (2220 100);
FORCEPROP 0 LAST $SEC 1
J 0
(2225 150);
DISPLAY 0.680851 (2225 150);
PAINT MONO (2225 150);
DISPLAY INVISIBLE (2225 150);
FORCEPROP 0 LAST CDS_SEC 1
J 0
(2225 150);
DISPLAY 1.021277 (2225 150);
DISPLAY INVISIBLE (2225 150);
FORCEPROP 1 LASTPIN (2175 75) $PN 1
J 0
(2180 37);
DISPLAY 0.787234 (2180 37);
PAINT MONO (2180 37);
FORCEPROP 1 LASTPIN (2175 -125) $PN 2
J 0
(2180 -115);
DISPLAY 0.787234 (2180 -115);
PAINT MONO (2180 -115);
FORCEPROP 1 LAST PACK_TYPE 0402LF
J 0
(2215 -150);
DISPLAY 0.638298 (2215 -150);
FORCEPROP 1 LAST WATTAGE 1/16W
J 0
(2215 -50);
DISPLAY 0.638298 (2215 -50);
FORCEPROP 1 LAST MATERIAL EMPTY
J 0
(2215 -100);
DISPLAY 0.638298 (2215 -100);
PAINT RED (2215 -100);
FORCEPROP 1 LAST TOLERANCE 5%
J 0
(2220 0);
DISPLAY 0.638298 (2220 0);
FORCEPROP 1 LAST VALUE 4.7K
J 0
(2220 50);
DISPLAY 0.638298 (2220 50);
FORCEPROP 2 LAST CDS_LIB pure_quanta
J 0
(2175 -25);
DISPLAY INVISIBLE (2175 -25);
FORCEPROP 1 LAST PATH I43
J 0
(2225 150);
DISPLAY 0.978723 (2225 150);
PAINT WHITE (2225 150);
DISPLAY INVISIBLE (2225 150);
FORCEPROP 1 LAST PART_NUMBER CS24702JB10
J 0
(2215 -200);
DISPLAY 0.638298 (2215 -200);
DISPLAY INVISIBLE (2215 -200);
FORCEADD UNIVERSAL_GND..1
(2175 -250);
FORCEPROP 3 LASTPIN (2175 -200) SIG_NAME GND\g
J 0
(2185 -190);
DISPLAY 0.659574 (2185 -190);
PAINT MONO (2185 -190);
DISPLAY INVISIBLE (2185 -190);
FORCEPROP 2 LAST CDS_LIB pure_quanta_power
J 0
(2175 -250);
DISPLAY INVISIBLE (2175 -250);
FORCEPROP 1 LAST HDL_POWER GND
J 1
(2200 -325);
DISPLAY 0.872340 (2200 -325);
PAINT GREEN (2200 -325);
DISPLAY INVISIBLE (2200 -325);
FORCEPROP 1 LAST PATH I44
J 0
(2250 -250);
DISPLAY 0.872340 (2250 -250);
PAINT AQUA (2250 -250);
DISPLAY INVISIBLE (2250 -250);
FORCEADD OFFPAGE..2
(3675 275);
FORCEPROP 2 LAST $XR0 241 
J 0
(3864 275);
DISPLAY 0.638298 (3864 275);
PAINT MONO (3864 275);
FORCEPROP 2 LAST CDS_LIB standard
J 0
(3675 275);
DISPLAY INVISIBLE (3675 275);
FORCEPROP 1 LAST OFFPAGE TRUE
J 0
(4000 150);
DISPLAY 0.872340 (4000 150);
PAINT AQUA (4000 150);
DISPLAY INVISIBLE (4000 150);
FORCEPROP 1 LAST COMMENT_BODY TRUE
J 0
(3630 180);
DISPLAY 0.872340 (3630 180);
PAINT GREEN (3630 180);
DISPLAY INVISIBLE (3630 180);
FORCEPROP 2 LAST PATH I45
J 0
(3875 325);
DISPLAY 1.021277 (3875 325);
DISPLAY INVISIBLE (3875 325);
FORCEADD UNIVERSAL_POWER..1
(2150 775);
FORCEPROP 3 LASTPIN (2150 725) SIG_NAME P3V3_AUX\g
J 0
(2160 735);
DISPLAY 0.659574 (2160 735);
PAINT MONO (2160 735);
DISPLAY INVISIBLE (2160 735);
FORCEPROP 1 LAST HDL_POWER P3V3_AUX
J 1
(2150 825);
DISPLAY 0.872340 (2150 825);
PAINT GREEN (2150 825);
FORCEPROP 2 LAST CDS_LIB pure_quanta_power
J 0
(2150 775);
PAINT MONO (2150 775);
DISPLAY INVISIBLE (2150 775);
FORCEPROP 1 LAST PATH I46
J 0
(2200 800);
DISPLAY 0.872340 (2200 800);
PAINT AQUA (2200 800);
DISPLAY INVISIBLE (2200 800);
FORCEADD Q_RES..2
(2150 525);
FORCEPROP 1 LAST LOCATION R4264
J 0
(2195 650);
DISPLAY 0.638298 (2195 650);
FORCEPROP 2 LAST $SEC 1
J 0
(2200 750);
DISPLAY 0.680851 (2200 750);
PAINT MONO (2200 750);
DISPLAY INVISIBLE (2200 750);
FORCEPROP 2 LAST CDS_SEC 1
J 0
(2200 750);
DISPLAY 1.021277 (2200 750);
DISPLAY INVISIBLE (2200 750);
FORCEPROP 1 LASTPIN (2150 625) $PN 1
J 0
(2155 587);
DISPLAY 0.787234 (2155 587);
FORCEPROP 1 LASTPIN (2150 425) $PN 2
J 0
(2155 435);
DISPLAY 0.787234 (2155 435);
FORCEPROP 1 LAST MATERIAL CHIP
J 0
(2190 450);
DISPLAY 0.638298 (2190 450);
FORCEPROP 1 LAST WATTAGE 1/16W
J 0
(2190 500);
DISPLAY 0.638298 (2190 500);
FORCEPROP 1 LAST PACK_TYPE 0402LF
J 0
(2190 400);
DISPLAY 0.638298 (2190 400);
FORCEPROP 1 LAST TOLERANCE 5%
J 0
(2195 550);
DISPLAY 0.638298 (2195 550);
FORCEPROP 1 LAST VALUE 4.7K
J 0
(2195 600);
DISPLAY 0.638298 (2195 600);
FORCEPROP 2 LAST CDS_LIB pure_quanta
J 0
(2150 525);
PAINT MONO (2150 525);
DISPLAY INVISIBLE (2150 525);
FORCEPROP 1 LAST PATH I47
J 0
(2200 700);
DISPLAY 0.978723 (2200 700);
PAINT WHITE (2200 700);
DISPLAY INVISIBLE (2200 700);
FORCEPROP 1 LAST PART_NUMBER CS24702JB10
J 0
(2190 350);
DISPLAY 0.638298 (2190 350);
DISPLAY INVISIBLE (2190 350);
FORCEADD Q_RES..1
(2400 275);
FORCEPROP 1 LAST LOCATION R4266
J 0
(2200 275);
DISPLAY 0.723404 (2200 275);
FORCEPROP 2 LAST $SEC 1
J 0
(2350 475);
DISPLAY 0.680851 (2350 475);
PAINT MONO (2350 475);
DISPLAY INVISIBLE (2350 475);
FORCEPROP 0 LAST CDS_SEC 1
J 0
(2100 350);
DISPLAY INVISIBLE (2100 350);
FORCEPROP 1 LASTPIN (2300 275) $PN 1
J 0
(2312 287);
DISPLAY 0.723404 (2312 287);
PAINT MONO (2312 287);
FORCEPROP 1 LASTPIN (2500 275) $PN 2
J 0
(2462 287);
DISPLAY 0.723404 (2462 287);
PAINT MONO (2462 287);
FORCEPROP 1 LAST VALUE 33.2
J 2
(2650 275);
DISPLAY 0.723404 (2650 275);
FORCEPROP 1 LAST PACK_TYPE 0402LF
J 0
(2225 225);
DISPLAY 0.723404 (2225 225);
FORCEPROP 1 LAST MATERIAL CHIP
J 0
(2425 225);
DISPLAY 0.723404 (2425 225);
FORCEPROP 1 LAST WATTAGE 1/16W
J 2
(2800 225);
DISPLAY 0.723404 (2800 225);
PAINT SKYBLUE (2800 225);
DISPLAY INVISIBLE (2800 225);
FORCEPROP 1 LAST TOLERANCE 1%
J 0
(2875 275);
DISPLAY 0.723404 (2875 275);
PAINT SKYBLUE (2875 275);
DISPLAY INVISIBLE (2875 275);
FORCEPROP 2 LAST CDS_LIB pure_quanta
J 0
(2400 275);
DISPLAY INVISIBLE (2400 275);
FORCEPROP 1 LAST PATH I48
J 0
(2350 425);
DISPLAY 0.978723 (2350 425);
PAINT WHITE (2350 425);
DISPLAY INVISIBLE (2350 425);
FORCEPROP 1 LAST PART_NUMBER CS03322FB03
J 0
(2000 175);
DISPLAY 0.723404 (2000 175);
PAINT WHITE (2000 175);
DISPLAY INVISIBLE (2000 175);
FORCEADD OFFPAGE..4
R 2
(-1375 -2075);
FORCEPROP 2 LAST $XR0 241 
J 0
(-1657 -2075);
DISPLAY 0.638298 (-1657 -2075);
PAINT MONO (-1657 -2075);
FORCEPROP 2 LAST CDS_LIB standard
J 0
(-1375 -2075);
DISPLAY INVISIBLE (-1375 -2075);
FORCEPROP 1 LAST OFFPAGE TRUE
J 2
(-1700 -2200);
DISPLAY 0.872340 (-1700 -2200);
PAINT GREEN (-1700 -2200);
DISPLAY INVISIBLE (-1700 -2200);
FORCEPROP 1 LAST COMMENT_BODY TRUE
J 2
(-1350 -2175);
DISPLAY 0.872340 (-1350 -2175);
PAINT GREEN (-1350 -2175);
DISPLAY INVISIBLE (-1350 -2175);
FORCEPROP 2 LAST PATH I49
J 0
(-1625 -2025);
DISPLAY 1.021277 (-1625 -2025);
DISPLAY INVISIBLE (-1625 -2025);
FORCEADD Q_RES..2
(-1100 -2275);
FORCEPROP 1 LAST LOCATION R4552
J 0
(-1055 -2150);
DISPLAY 0.978723 (-1055 -2150);
FORCEPROP 0 LAST $SEC 1
J 0
(-1050 -2100);
DISPLAY 0.680851 (-1050 -2100);
PAINT MONO (-1050 -2100);
DISPLAY INVISIBLE (-1050 -2100);
FORCEPROP 0 LAST CDS_SEC 1
J 0
(-1050 -2100);
DISPLAY 1.021277 (-1050 -2100);
DISPLAY INVISIBLE (-1050 -2100);
FORCEPROP 1 LASTPIN (-1100 -2175) $PN 1
J 0
(-1095 -2213);
DISPLAY 0.787234 (-1095 -2213);
PAINT MONO (-1095 -2213);
FORCEPROP 1 LASTPIN (-1100 -2375) $PN 2
J 0
(-1095 -2365);
DISPLAY 0.787234 (-1095 -2365);
PAINT MONO (-1095 -2365);
FORCEPROP 1 LAST MATERIAL CHIP
J 0
(-1060 -2350);
DISPLAY 0.510638 (-1060 -2350);
FORCEPROP 1 LAST WATTAGE 1/16W
J 0
(-1060 -2300);
DISPLAY 0.510638 (-1060 -2300);
FORCEPROP 1 LAST TOLERANCE 1%
J 0
(-1055 -2250);
DISPLAY 0.510638 (-1055 -2250);
FORCEPROP 1 LAST VALUE 100K
J 0
(-1055 -2200);
DISPLAY 0.510638 (-1055 -2200);
FORCEPROP 1 LAST PACK_TYPE 0402LF
J 0
(-1060 -2450);
DISPLAY 0.510638 (-1060 -2450);
FORCEPROP 2 LAST CDS_LIB pure_quanta
J 0
(-1100 -2275);
DISPLAY INVISIBLE (-1100 -2275);
FORCEPROP 1 LAST PATH I50
J 0
(-1050 -2100);
DISPLAY 0.978723 (-1050 -2100);
PAINT WHITE (-1050 -2100);
DISPLAY INVISIBLE (-1050 -2100);
FORCEPROP 1 LAST PART_NUMBER CS41002FB09
J 0
(-1060 -2400);
DISPLAY 0.510638 (-1060 -2400);
DISPLAY INVISIBLE (-1060 -2400);
FORCEADD Q_RES..2
(-1125 -1800);
FORCEPROP 1 LAST LOCATION R4551
J 0
(-1080 -1675);
DISPLAY 0.978723 (-1080 -1675);
FORCEPROP 0 LAST $SEC 1
J 0
(-1075 -1625);
DISPLAY 0.680851 (-1075 -1625);
PAINT MONO (-1075 -1625);
DISPLAY INVISIBLE (-1075 -1625);
FORCEPROP 0 LAST CDS_SEC 1
J 0
(-1075 -1625);
DISPLAY 1.021277 (-1075 -1625);
DISPLAY INVISIBLE (-1075 -1625);
FORCEPROP 1 LASTPIN (-1125 -1700) $PN 1
J 0
(-1120 -1738);
DISPLAY 0.787234 (-1120 -1738);
PAINT MONO (-1120 -1738);
FORCEPROP 1 LASTPIN (-1125 -1900) $PN 2
J 0
(-1120 -1890);
DISPLAY 0.787234 (-1120 -1890);
PAINT MONO (-1120 -1890);
FORCEPROP 1 LAST WATTAGE 1/16W
J 0
(-1085 -1825);
DISPLAY 0.787234 (-1085 -1825);
FORCEPROP 1 LAST PACK_TYPE 0402LF
J 0
(-1085 -1975);
DISPLAY 0.787234 (-1085 -1975);
FORCEPROP 1 LAST MATERIAL EMPTY
J 0
(-1085 -1875);
DISPLAY 0.787234 (-1085 -1875);
PAINT RED (-1085 -1875);
FORCEPROP 1 LAST TOLERANCE 1%
J 0
(-1080 -1775);
DISPLAY 0.787234 (-1080 -1775);
FORCEPROP 1 LAST VALUE 54.9K
J 0
(-1080 -1725);
DISPLAY 0.787234 (-1080 -1725);
FORCEPROP 2 LAST CDS_LIB pure_quanta
J 0
(-1125 -1800);
DISPLAY INVISIBLE (-1125 -1800);
FORCEPROP 1 LAST PATH I51
J 0
(-1075 -1625);
DISPLAY 0.978723 (-1075 -1625);
PAINT WHITE (-1075 -1625);
DISPLAY INVISIBLE (-1075 -1625);
FORCEPROP 1 LAST PART_NUMBER CS35492FB03
J 0
(-1085 -1925);
DISPLAY 0.787234 (-1085 -1925);
DISPLAY INVISIBLE (-1085 -1925);
FORCEADD UNIVERSAL_POWER..1
(-1125 -1550);
FORCEPROP 3 LASTPIN (-1125 -1600) SIG_NAME P3V3_AUX\g
J 0
(-1115 -1590);
DISPLAY 0.659574 (-1115 -1590);
PAINT MONO (-1115 -1590);
DISPLAY INVISIBLE (-1115 -1590);
FORCEPROP 1 LAST HDL_POWER P3V3_AUX
J 1
(-1125 -1500);
DISPLAY 0.872340 (-1125 -1500);
PAINT GREEN (-1125 -1500);
FORCEPROP 2 LAST CDS_LIB pure_quanta_power
J 0
(-1125 -1550);
PAINT MONO (-1125 -1550);
DISPLAY INVISIBLE (-1125 -1550);
FORCEPROP 1 LAST PATH I52
J 0
(-1075 -1525);
DISPLAY 0.872340 (-1075 -1525);
PAINT AQUA (-1075 -1525);
DISPLAY INVISIBLE (-1075 -1525);
FORCEADD MOSFET_NCH_DUAL..1
(0 -2025);
FORCEPROP 1 LAST LOCATION Q145
J 0
(151 -2051);
DISPLAY 0.723404 (151 -2051);
PAINT GREEN (151 -2051);
FORCEPROP 0 LAST $SEC 1
J 0
(175 -1900);
DISPLAY 0.680851 (175 -1900);
PAINT MONO (175 -1900);
DISPLAY INVISIBLE (175 -1900);
FORCEPROP 2 LAST CDS_SEC 1
J 0
(175 -1900);
DISPLAY 1.021277 (175 -1900);
DISPLAY INVISIBLE (175 -1900);
FORCEPROP 0 LASTPIN (50 -1825) $PN 6
R 1
J 0
(40 -1815);
DISPLAY 0.680851 (40 -1815);
PAINT MONO (40 -1815);
FORCEPROP 0 LASTPIN (-200 -2075) $PN 2
J 2
(-210 -2065);
DISPLAY 0.680851 (-210 -2065);
PAINT MONO (-210 -2065);
FORCEPROP 0 LASTPIN (50 -2225) $PN 1
R 1
J 2
(40 -2235);
DISPLAY 0.680851 (40 -2235);
PAINT MONO (40 -2235);
FORCEPROP 2 LAST VALUE PJT138K
J 0
(175 -2000);
DISPLAY 1.021277 (175 -2000);
FORCEPROP 1 LAST MATERIAL IC
J 0
(151 -2176);
DISPLAY 0.723404 (151 -2176);
PAINT GREEN (151 -2176);
FORCEPROP 2 LAST PART_TYPE SMLF
J 0
(175 -1950);
DISPLAY 1.021277 (175 -1950);
FORCEPROP 1 LAST CDS_LMAN_SYM_OUTLINE -150,150,150,-150
J 0
(0 -2025);
DISPLAY 0.468085 (0 -2025);
PAINT GREEN (0 -2025);
DISPLAY INVISIBLE (0 -2025);
FORCEPROP 1 LAST NEEDS_NO_SIZE TRUE
J 0
(0 -2026);
DISPLAY 0.468085 (0 -2026);
PAINT GREEN (0 -2026);
DISPLAY INVISIBLE (0 -2026);
FORCEPROP 2 LAST CDS_LIB pure_quanta
J 0
(0 -2025);
DISPLAY INVISIBLE (0 -2025);
FORCEPROP 1 LAST PATH I53
J 0
(0 -2025);
DISPLAY 0.723404 (0 -2025);
PAINT GREEN (0 -2025);
DISPLAY INVISIBLE (0 -2025);
FORCEPROP 1 LAST PART_NUMBER BAM138K0003
J 0
(151 -2111);
DISPLAY 0.723404 (151 -2111);
PAINT GREEN (151 -2111);
DISPLAY INVISIBLE (151 -2111);
FORCEADD UNIVERSAL_GND..1
(50 -2400);
FORCEPROP 3 LASTPIN (50 -2350) SIG_NAME GND\g
J 0
(60 -2340);
DISPLAY 0.659574 (60 -2340);
PAINT MONO (60 -2340);
DISPLAY INVISIBLE (60 -2340);
FORCEPROP 2 LAST CDS_LIB pure_quanta_power
J 0
(50 -2400);
DISPLAY INVISIBLE (50 -2400);
FORCEPROP 1 LAST HDL_POWER GND
J 1
(75 -2475);
DISPLAY 0.872340 (75 -2475);
PAINT GREEN (75 -2475);
DISPLAY INVISIBLE (75 -2475);
FORCEPROP 1 LAST PATH I54
J 0
(125 -2400);
DISPLAY 0.872340 (125 -2400);
PAINT AQUA (125 -2400);
DISPLAY INVISIBLE (125 -2400);
FORCEADD Q_RES..2
(50 -1425);
FORCEPROP 1 LAST LOCATION R4553
J 0
(95 -1300);
DISPLAY 0.638298 (95 -1300);
FORCEPROP 2 LAST $SEC 1
J 0
(100 -1200);
DISPLAY 0.680851 (100 -1200);
PAINT MONO (100 -1200);
DISPLAY INVISIBLE (100 -1200);
FORCEPROP 2 LAST CDS_SEC 1
J 0
(100 -1200);
DISPLAY 1.021277 (100 -1200);
DISPLAY INVISIBLE (100 -1200);
FORCEPROP 1 LASTPIN (50 -1325) $PN 1
J 0
(55 -1363);
DISPLAY 0.787234 (55 -1363);
FORCEPROP 1 LASTPIN (50 -1525) $PN 2
J 0
(55 -1515);
DISPLAY 0.787234 (55 -1515);
FORCEPROP 1 LAST VALUE 4.7K
J 0
(95 -1350);
DISPLAY 0.638298 (95 -1350);
FORCEPROP 1 LAST TOLERANCE 5%
J 0
(95 -1400);
DISPLAY 0.638298 (95 -1400);
FORCEPROP 1 LAST WATTAGE 1/16W
J 0
(90 -1450);
DISPLAY 0.638298 (90 -1450);
FORCEPROP 1 LAST MATERIAL CHIP
J 0
(90 -1500);
DISPLAY 0.638298 (90 -1500);
FORCEPROP 1 LAST PACK_TYPE 0402LF
J 0
(90 -1550);
DISPLAY 0.638298 (90 -1550);
FORCEPROP 2 LAST CDS_LIB pure_quanta
J 0
(50 -1425);
PAINT MONO (50 -1425);
DISPLAY INVISIBLE (50 -1425);
FORCEPROP 1 LAST PATH I55
J 0
(100 -1250);
DISPLAY 0.978723 (100 -1250);
PAINT WHITE (100 -1250);
DISPLAY INVISIBLE (100 -1250);
FORCEPROP 1 LAST PART_NUMBER CS24702JB10
J 0
(90 -1600);
DISPLAY 0.638298 (90 -1600);
DISPLAY INVISIBLE (90 -1600);
FORCEADD UNIVERSAL_POWER..1
(50 -1200);
FORCEPROP 3 LASTPIN (50 -1250) SIG_NAME P3V3_AUX\g
J 0
(60 -1240);
DISPLAY 0.659574 (60 -1240);
PAINT MONO (60 -1240);
DISPLAY INVISIBLE (60 -1240);
FORCEPROP 1 LAST HDL_POWER P3V3_AUX
J 1
(50 -1150);
DISPLAY 0.872340 (50 -1150);
PAINT GREEN (50 -1150);
FORCEPROP 2 LAST CDS_LIB pure_quanta_power
J 0
(50 -1200);
PAINT MONO (50 -1200);
DISPLAY INVISIBLE (50 -1200);
FORCEPROP 1 LAST PATH I56
J 0
(100 -1175);
DISPLAY 0.872340 (100 -1175);
PAINT AQUA (100 -1175);
DISPLAY INVISIBLE (100 -1175);
FORCEADD UNIVERSAL_GND..1
(1200 -2100);
FORCEPROP 3 LASTPIN (1200 -2050) SIG_NAME GND\g
J 0
(1210 -2040);
DISPLAY 0.659574 (1210 -2040);
PAINT MONO (1210 -2040);
DISPLAY INVISIBLE (1210 -2040);
FORCEPROP 2 LAST CDS_LIB pure_quanta_power
J 0
(1200 -2100);
DISPLAY INVISIBLE (1200 -2100);
FORCEPROP 1 LAST HDL_POWER GND
J 1
(1225 -2175);
DISPLAY 0.872340 (1225 -2175);
PAINT GREEN (1225 -2175);
DISPLAY INVISIBLE (1225 -2175);
FORCEPROP 1 LAST PATH I57
J 0
(1275 -2100);
DISPLAY 0.872340 (1275 -2100);
PAINT AQUA (1275 -2100);
DISPLAY INVISIBLE (1275 -2100);
FORCEADD MOSFET_NCH_DUAL..2
(1150 -1725);
FORCEPROP 1 LAST LOCATION Q145
J 0
(1301 -1749);
DISPLAY 0.723404 (1301 -1749);
PAINT GREEN (1301 -1749);
FORCEPROP 0 LAST $SEC 2
J 0
(1325 -1600);
DISPLAY 0.680851 (1325 -1600);
PAINT MONO (1325 -1600);
DISPLAY INVISIBLE (1325 -1600);
FORCEPROP 0 LAST CDS_SEC 2
J 0
(1325 -1600);
DISPLAY 1.021277 (1325 -1600);
DISPLAY INVISIBLE (1325 -1600);
FORCEPROP 0 LASTPIN (1200 -1525) $PN 3
R 1
J 0
(1190 -1515);
DISPLAY 0.680851 (1190 -1515);
PAINT MONO (1190 -1515);
FORCEPROP 0 LASTPIN (950 -1775) $PN 5
J 2
(940 -1765);
DISPLAY 0.680851 (940 -1765);
PAINT MONO (940 -1765);
FORCEPROP 0 LASTPIN (1200 -1925) $PN 4
R 1
J 2
(1190 -1935);
DISPLAY 0.680851 (1190 -1935);
PAINT MONO (1190 -1935);
FORCEPROP 2 LAST PART_TYPE SMLF
J 0
(1325 -1650);
DISPLAY 1.021277 (1325 -1650);
FORCEPROP 1 LAST MATERIAL IC
J 0
(1301 -1874);
DISPLAY 0.723404 (1301 -1874);
PAINT GREEN (1301 -1874);
FORCEPROP 2 LAST VALUE PJT138K
J 0
(1325 -1700);
DISPLAY 1.021277 (1325 -1700);
FORCEPROP 2 LAST CDS_LIB pure_quanta
J 0
(1150 -1725);
DISPLAY INVISIBLE (1150 -1725);
FORCEPROP 1 LAST NEEDS_NO_SIZE TRUE
J 0
(1300 -1834);
DISPLAY 0.468085 (1300 -1834);
PAINT GREEN (1300 -1834);
DISPLAY INVISIBLE (1300 -1834);
FORCEPROP 1 LAST CDS_LMAN_SYM_OUTLINE -150,150,150,-150
J 0
(1150 -1725);
DISPLAY 0.468085 (1150 -1725);
PAINT GREEN (1150 -1725);
DISPLAY INVISIBLE (1150 -1725);
FORCEPROP 1 LAST PATH I58
J 0
(1300 -1875);
DISPLAY 0.723404 (1300 -1875);
PAINT GREEN (1300 -1875);
DISPLAY INVISIBLE (1300 -1875);
FORCEPROP 1 LAST PART_NUMBER BAM138K0003
J 0
(1301 -1819);
DISPLAY 0.723404 (1301 -1819);
PAINT GREEN (1301 -1819);
DISPLAY INVISIBLE (1301 -1819);
FORCEADD Q_RES..2
(1200 -1300);
FORCEPROP 1 LAST LOCATION R4554
J 0
(1245 -1175);
DISPLAY 0.638298 (1245 -1175);
FORCEPROP 2 LAST $SEC 1
J 0
(1250 -1075);
DISPLAY 0.680851 (1250 -1075);
PAINT MONO (1250 -1075);
DISPLAY INVISIBLE (1250 -1075);
FORCEPROP 2 LAST CDS_SEC 1
J 0
(1250 -1075);
DISPLAY 1.021277 (1250 -1075);
DISPLAY INVISIBLE (1250 -1075);
FORCEPROP 1 LASTPIN (1200 -1200) $PN 1
J 0
(1205 -1238);
DISPLAY 0.787234 (1205 -1238);
FORCEPROP 1 LASTPIN (1200 -1400) $PN 2
J 0
(1205 -1390);
DISPLAY 0.787234 (1205 -1390);
FORCEPROP 1 LAST MATERIAL CHIP
J 0
(1240 -1375);
DISPLAY 0.638298 (1240 -1375);
FORCEPROP 1 LAST PACK_TYPE 0402LF
J 0
(1240 -1425);
DISPLAY 0.638298 (1240 -1425);
FORCEPROP 1 LAST VALUE 100K
J 0
(1245 -1225);
DISPLAY 0.638298 (1245 -1225);
FORCEPROP 1 LAST TOLERANCE 1%
J 0
(1245 -1275);
DISPLAY 0.638298 (1245 -1275);
FORCEPROP 1 LAST WATTAGE 1/16W
J 0
(1240 -1325);
DISPLAY 0.638298 (1240 -1325);
FORCEPROP 2 LAST CDS_LIB pure_quanta
J 0
(1200 -1300);
PAINT MONO (1200 -1300);
DISPLAY INVISIBLE (1200 -1300);
FORCEPROP 1 LAST PATH I59
J 0
(1250 -1125);
DISPLAY 0.978723 (1250 -1125);
PAINT WHITE (1250 -1125);
DISPLAY INVISIBLE (1250 -1125);
FORCEPROP 1 LAST PART_NUMBER CS41002FB09
J 0
(1240 -1475);
DISPLAY 0.638298 (1240 -1475);
DISPLAY INVISIBLE (1240 -1475);
FORCEADD UNIVERSAL_GND..1
(-1775 2425);
FORCEPROP 3 LASTPIN (-1775 2475) SIG_NAME GND\g
J 0
(-1765 2485);
DISPLAY 0.659574 (-1765 2485);
PAINT MONO (-1765 2485);
DISPLAY INVISIBLE (-1765 2485);
FORCEPROP 2 LAST CDS_LIB pure_quanta_power
J 0
(-1775 2425);
DISPLAY INVISIBLE (-1775 2425);
FORCEPROP 1 LAST HDL_POWER GND
J 1
(-1750 2350);
DISPLAY 0.872340 (-1750 2350);
PAINT GREEN (-1750 2350);
DISPLAY INVISIBLE (-1750 2350);
FORCEPROP 1 LAST PATH I6
J 0
(-1700 2425);
DISPLAY 0.872340 (-1700 2425);
PAINT AQUA (-1700 2425);
DISPLAY INVISIBLE (-1700 2425);
FORCEADD UNIVERSAL_POWER..1
(1200 -1075);
FORCEPROP 3 LASTPIN (1200 -1125) SIG_NAME P3V3_AUX\g
J 0
(1210 -1115);
DISPLAY 0.659574 (1210 -1115);
PAINT MONO (1210 -1115);
DISPLAY INVISIBLE (1210 -1115);
FORCEPROP 1 LAST HDL_POWER P3V3_AUX
J 1
(1200 -1025);
DISPLAY 0.872340 (1200 -1025);
PAINT GREEN (1200 -1025);
FORCEPROP 2 LAST CDS_LIB pure_quanta_power
J 0
(1200 -1075);
PAINT MONO (1200 -1075);
DISPLAY INVISIBLE (1200 -1075);
FORCEPROP 1 LAST PATH I60
J 0
(1250 -1050);
DISPLAY 0.872340 (1250 -1050);
PAINT AQUA (1250 -1050);
DISPLAY INVISIBLE (1250 -1050);
FORCEADD UNIVERSAL_GND..1
(1975 -1975);
FORCEPROP 3 LASTPIN (1975 -1925) SIG_NAME GND\g
J 0
(1985 -1915);
DISPLAY 0.659574 (1985 -1915);
PAINT MONO (1985 -1915);
DISPLAY INVISIBLE (1985 -1915);
FORCEPROP 2 LAST CDS_LIB pure_quanta_power
J 0
(1975 -1975);
DISPLAY INVISIBLE (1975 -1975);
FORCEPROP 1 LAST HDL_POWER GND
J 1
(2000 -2050);
DISPLAY 0.872340 (2000 -2050);
PAINT GREEN (2000 -2050);
DISPLAY INVISIBLE (2000 -2050);
FORCEPROP 1 LAST PATH I61
J 0
(2050 -1975);
DISPLAY 0.872340 (2050 -1975);
PAINT AQUA (2050 -1975);
DISPLAY INVISIBLE (2050 -1975);
FORCEADD Q_CAP..1
(1975 -1775);
FORCEPROP 1 LAST LOCATION C70
J 0
(2025 -1675);
DISPLAY 0.978723 (2025 -1675);
FORCEPROP 0 LAST $SEC 1
J 0
(2025 -1625);
DISPLAY 0.680851 (2025 -1625);
PAINT MONO (2025 -1625);
DISPLAY INVISIBLE (2025 -1625);
FORCEPROP 0 LAST CDS_SEC 1
J 0
(2025 -1625);
DISPLAY 1.021277 (2025 -1625);
DISPLAY INVISIBLE (2025 -1625);
FORCEPROP 1 LASTPIN (1975 -1675) $PN 1
J 0
(1985 -1695);
DISPLAY 0.787234 (1985 -1695);
PAINT MONO (1985 -1695);
FORCEPROP 1 LASTPIN (1975 -1875) $PN 2
J 0
(1985 -1895);
DISPLAY 0.787234 (1985 -1895);
PAINT MONO (1985 -1895);
FORCEPROP 1 LAST VALUE 0.1UF
J 0
(2025 -1725);
DISPLAY 0.638298 (2025 -1725);
FORCEPROP 1 LAST VOLTAGE 25V
J 0
(2025 -1775);
DISPLAY 0.638298 (2025 -1775);
FORCEPROP 1 LAST TOLERANCE 10%
J 0
(2025 -1825);
DISPLAY 0.638298 (2025 -1825);
FORCEPROP 1 LAST MATERIAL X7R
J 0
(2025 -1875);
DISPLAY 0.638298 (2025 -1875);
PAINT RED (2025 -1875);
FORCEPROP 1 LAST PACK_TYPE 0402
J 0
(2025 -1975);
DISPLAY 0.638298 (2025 -1975);
FORCEPROP 2 LAST CDS_LIB pure_quanta
J 0
(1975 -1775);
DISPLAY INVISIBLE (1975 -1775);
FORCEPROP 1 LAST PATH I62
J 0
(2025 -1625);
DISPLAY 0.978723 (2025 -1625);
PAINT WHITE (2025 -1625);
DISPLAY INVISIBLE (2025 -1625);
FORCEPROP 1 LAST PART_NUMBER CH4104K1B00
J 0
(2025 -1925);
DISPLAY 0.638298 (2025 -1925);
DISPLAY INVISIBLE (2025 -1925);
FORCEADD OFFPAGE..2
(2325 -1475);
FORCEPROP 2 LAST $XR0 81 
J 0
(2514 -1475);
DISPLAY 0.638298 (2514 -1475);
PAINT MONO (2514 -1475);
FORCEPROP 2 LAST CDS_LIB standard
J 0
(2325 -1475);
DISPLAY INVISIBLE (2325 -1475);
FORCEPROP 1 LAST OFFPAGE TRUE
J 0
(2650 -1600);
DISPLAY 0.872340 (2650 -1600);
PAINT AQUA (2650 -1600);
DISPLAY INVISIBLE (2650 -1600);
FORCEPROP 1 LAST COMMENT_BODY TRUE
J 0
(2280 -1570);
DISPLAY 0.872340 (2280 -1570);
PAINT GREEN (2280 -1570);
DISPLAY INVISIBLE (2280 -1570);
FORCEPROP 2 LAST PATH I63
J 0
(2525 -1425);
DISPLAY 1.021277 (2525 -1425);
DISPLAY INVISIBLE (2525 -1425);
FORCEADD UNIVERSAL_GND..1
(-1100 -2550);
FORCEPROP 3 LASTPIN (-1100 -2500) SIG_NAME GND\g
J 0
(-1090 -2490);
DISPLAY 0.659574 (-1090 -2490);
PAINT MONO (-1090 -2490);
DISPLAY INVISIBLE (-1090 -2490);
FORCEPROP 2 LAST CDS_LIB pure_quanta_power
J 0
(-1100 -2550);
DISPLAY INVISIBLE (-1100 -2550);
FORCEPROP 1 LAST HDL_POWER GND
J 1
(-1075 -2625);
DISPLAY 0.872340 (-1075 -2625);
PAINT GREEN (-1075 -2625);
DISPLAY INVISIBLE (-1075 -2625);
FORCEPROP 1 LAST PATH I64
J 0
(-1025 -2550);
DISPLAY 0.872340 (-1025 -2550);
PAINT AQUA (-1025 -2550);
DISPLAY INVISIBLE (-1025 -2550);
FORCEADD OFFPAGE..4
R 2
(-2025 2825);
FORCEPROP 2 LAST $XR0 81 
J 0
(-2276 2825);
DISPLAY 0.638298 (-2276 2825);
PAINT MONO (-2276 2825);
FORCEPROP 2 LAST CDS_LIB standard
J 0
(-2025 2825);
DISPLAY INVISIBLE (-2025 2825);
FORCEPROP 1 LAST OFFPAGE TRUE
J 2
(-2350 2700);
DISPLAY 0.872340 (-2350 2700);
PAINT GREEN (-2350 2700);
DISPLAY INVISIBLE (-2350 2700);
FORCEPROP 1 LAST COMMENT_BODY TRUE
J 2
(-2000 2725);
DISPLAY 0.872340 (-2000 2725);
PAINT GREEN (-2000 2725);
DISPLAY INVISIBLE (-2000 2725);
FORCEPROP 2 LAST PATH I7
J 0
(-2300 2875);
DISPLAY 1.021277 (-2300 2875);
DISPLAY INVISIBLE (-2300 2875);
FORCEADD DNS..2
(-1800 3075);
PAINT RED (-1800 3075);
FORCEPROP 2 LAST CDS_LIB mstr_misc
J 0
(-1800 3075);
DISPLAY INVISIBLE (-1800 3075);
FORCEPROP 1 LAST COMMENT_BODY TRUE
J 0
(-1800 3075);
DISPLAY INVISIBLE (-1800 3075);
FORCEADD DNS..2
(-1125 -1825);
PAINT RED (-1125 -1825);
FORCEPROP 2 LAST CDS_LIB mstr_misc
J 0
(-1125 -1825);
DISPLAY INVISIBLE (-1125 -1825);
FORCEPROP 1 LAST COMMENT_BODY TRUE
J 0
(-1125 -1825);
DISPLAY INVISIBLE (-1125 -1825);
FORCEADD QUANTA_TITLE_BLOCK_C..1
(4975 -2975);
FORCEPROP 0 LAST CDS_CON_LAST_MODIFIED Thu Sep 14 16:12:32 2023
J 0
(3090 -2960);
DISPLAY INVISIBLE (3090 -2960);
FORCEPROP 1 LAST CUSTOM_TXT_CDS <CON_LAST_MODIFIED>
J 0
(3090 -2960);
DISPLAY 0.978723 (3090 -2960);
FORCEPROP 2 LAST CUSTOM_TXT_CDS <XR_PAGE_TITLE>
J 0
(-2915 2275);
DISPLAY 0.638298 (-2915 2275);
PAINT PINK (-2915 2275);
DISPLAY INVISIBLE (-2915 2275);
FORCEPROP 1 LAST CUSTOM_TXT_CDS <NAME_2>
J 0
(1800 -2925);
FORCEPROP 1 LAST CUSTOM_TXT_CDS <NAME_1>
J 0
(1800 -2800);
FORCEPROP 1 LAST CUSTOM_TXT_CDS <Q_NUMBER>
J 0
(3572 -2872);
DISPLAY 1.212766 (3572 -2872);
FORCEPROP 1 LAST CUSTOM_TXT_CDS <Q_PROJ>
J 0
(2593 -2873);
DISPLAY 1.212766 (2593 -2873);
FORCEPROP 1 LAST CUSTOM_TXT_CDS <Q_REV>
J 0
(4791 -2872);
DISPLAY 1.212766 (4791 -2872);
FORCEPROP 1 LAST CUSTOM_TXT_CDS <CON_PAGE_NUM> OF <CON_TOTAL_PAGES>
J 0
(4529 -2957);
DISPLAY 0.978723 (4529 -2957);
FORCEPROP 1 LAST Q_TITLE POWER CONNECTOR/ISOLATED
J 0
(-4391 -2949);
DISPLAY 2.446809 (-4391 -2949);
PAINT GREEN (-4391 -2949);
FORCEPROP 2 LAST CDS_LIB pure_quanta
J 0
(4975 -2975);
DISPLAY INVISIBLE (4975 -2975);
FORCEPROP 1 LAST CDS_LMAN_SYM_OUTLINE -9475,6775,100,-125
J 0
(4975 -2975);
DISPLAY 0.468085 (4975 -2975);
PAINT GREEN (4975 -2975);
DISPLAY INVISIBLE (4975 -2975);
FORCEPROP 2 LAST PAGE_BORDER TRUE
J 0
(-2915 2275);
DISPLAY 0.638298 (-2915 2275);
PAINT PINK (-2915 2275);
DISPLAY INVISIBLE (-2915 2275);
FORCEPROP 2 LAST CDS_XR_PAGE_TITLE CR-242 : @T6G_MB_LIB.T6G(SCH_1):PAGE242
J 0
(-2915 2275);
DISPLAY 0.638298 (-2915 2275);
PAINT PINK (-2915 2275);
DISPLAY INVISIBLE (-2915 2275);
FORCEPROP 1 LAST Q_DEPT BU9
J 1
(1212 -2926);
DISPLAY 1.957447 (1212 -2926);
PAINT GREEN (1212 -2926);
DISPLAY INVISIBLE (1212 -2926);
FORCEPROP 1 LAST COMMENT_BODY TRUE
J 0
(4987 -2988);
DISPLAY 0.978723 (4987 -2988);
PAINT GREEN (4987 -2988);
DISPLAY INVISIBLE (4987 -2988);
FORCEADD DNS..2
(1750 1750);
PAINT RED (1750 1750);
FORCEPROP 2 LAST CDS_LIB mstr_misc
J 0
(1750 1750);
DISPLAY INVISIBLE (1750 1750);
FORCEPROP 1 LAST COMMENT_BODY TRUE
J 0
(1750 1750);
DISPLAY INVISIBLE (1750 1750);
FORCEADD DNS..2
(1725 2300);
PAINT RED (1725 2300);
FORCEPROP 2 LAST CDS_LIB mstr_misc
J 0
(1725 2300);
DISPLAY INVISIBLE (1725 2300);
FORCEPROP 1 LAST COMMENT_BODY TRUE
J 0
(1725 2300);
DISPLAY INVISIBLE (1725 2300);
FORCEADD DNS..2
(2175 -50);
PAINT RED (2175 -50);
FORCEPROP 2 LAST CDS_LIB mstr_misc
J 0
(2175 -50);
DISPLAY INVISIBLE (2175 -50);
FORCEPROP 1 LAST COMMENT_BODY TRUE
J 0
(2175 -50);
DISPLAY INVISIBLE (2175 -50);
WIRE 16 -1 (-1800 3300)(-1800 3200);
WIRE 16 -1 (-150 2025)(-50 2025);
WIRE 16 -1 (-150 2025)(-150 1900);
WIRE 16 -1 (925 2375)(925 2300);
WIRE 16 -1 (1750 1675)(1750 1600);
WIRE 16 -1 (1725 2525)(1725 2425);
WIRE 16 -1 (225 225)(-25 225);
WIRE 16 -1 (-25 225)(-25 125);
WIRE 16 -1 (1250 -450)(1250 -525);
WIRE 16 -1 (2175 -125)(2175 -200);
WIRE 16 -1 (2150 725)(2150 625);
WIRE 16 -1 (-1125 -1600)(-1125 -1700);
WIRE 16 -1 (50 -2225)(50 -2350);
WIRE 16 -1 (50 -1250)(50 -1325);
WIRE 16 -1 (1200 -1925)(1200 -2050);
WIRE 16 -1 (-1775 2475)(-1775 2525);
WIRE 16 -1 (1200 -1125)(1200 -1200);
WIRE 16 -1 (1975 -1875)(1975 -1925);
WIRE 16 -1 (-1100 -2375)(-1100 -2500);
WIRE 16 -1 (-2125 275)(-1225 275);
FORCEPROP 2 LAST SIG_NAME PWRGD_P3V3_AUX_PDB
J 0
(-2060 285);
DISPLAY 0.851064 (-2060 285);
PAINT WHITE (-2060 285);
WIRE 16 -1 (50 -1825)(50 -1775);
WIRE 16 -1 (950 -1775)(50 -1775);
FORCEPROP 2 LAST SIG_NAME HPDB_HSC_PWRGD_N
J 0
(65 -1765);
DISPLAY 1.021277 (65 -1765);
FORCEPROP 2 LASTPROP $XRERR UNIQUE?
J 0
(-175 -1765);
DISPLAY 0.638298 (-175 -1765);
PAINT MONO (-175 -1765);
DISPLAY INVISIBLE (-175 -1765);
WIRE 16 -1 (50 -1525)(50 -1775);
WIRE 16 -1 (-1225 2125)(-50 2125);
FORCEPROP 2 LAST SIG_NAME GPU_PRSNT_R
J 0
(-760 2135);
DISPLAY 0.808511 (-760 2135);
PAINT WHITE (-760 2135);
FORCEPROP 2 LASTPROP $XRERR UNIQUE?
J 0
(-1000 2135);
DISPLAY 0.638298 (-1000 2135);
PAINT MONO (-1000 2135);
DISPLAY INVISIBLE (-1000 2135);
WIRE 16 -1 (-1100 -2175)(-1100 -2075);
WIRE 16 -1 (-200 -2075)(-1100 -2075);
FORCEPROP 2 LAST SIG_NAME HPDB_HSC_PWRGD
J 0
(-1060 -2065);
DISPLAY 0.808511 (-1060 -2065);
WIRE 16 -1 (-1100 -2075)(-1125 -2075);
WIRE 16 -1 (-1125 -1900)(-1125 -2075);
WIRE 16 -1 (-1125 -2075)(-1325 -2075);
WIRE 16 -1 (-1800 2825)(-1775 2825);
WIRE 16 -1 (-1800 3000)(-1800 2825);
WIRE 16 -1 (-1800 2825)(-1975 2825);
WIRE 16 -1 (-450 2825)(-1775 2825);
FORCEPROP 2 LAST SIG_NAME FM_GPU_HSC_EN
J 0
(-1510 2835);
DISPLAY 0.808511 (-1510 2835);
PAINT WHITE (-1510 2835);
WIRE 16 -1 (-1775 2725)(-1775 2825);
WIRE 16 -1 (-450 2825)(-450 2225);
WIRE 16 -1 (-450 2225)(-50 2225);
WIRE 16 -1 (-1975 2125)(-1425 2125);
FORCEPROP 2 LAST SIG_NAME GPU_PRSNT
J 0
(-1935 2135);
DISPLAY 0.808511 (-1935 2135);
PAINT WHITE (-1935 2135);
WIRE 16 -1 (1750 1875)(1750 2075);
WIRE 16 -1 (1750 2075)(1900 2075);
WIRE 16 -1 (1725 2075)(1750 2075);
WIRE 16 -1 (1725 2225)(1725 2075);
WIRE 16 -1 (1725 2075)(550 2075);
FORCEPROP 2 LAST SIG_NAME FM_GPU_HSC_EN_BUF_R
J 0
(1015 2085);
DISPLAY 0.638298 (1015 2085);
PAINT WHITE (1015 2085);
FORCEPROP 2 LASTPROP $XRERR UNIQUE?
J 0
(775 2085);
DISPLAY 0.638298 (775 2085);
PAINT MONO (775 2085);
DISPLAY INVISIBLE (775 2085);
WIRE 16 -1 (925 2750)(925 2675);
WIRE 16 -1 (925 2675)(925 2575);
WIRE 16 -1 (925 2675)(800 2675);
WIRE 16 -1 (800 2225)(800 2675);
WIRE 16 -1 (550 2225)(800 2225);
WIRE 16 -1 (1250 -175)(1250 -250);
WIRE 16 -1 (1250 -75)(1250 -175);
WIRE 16 -1 (1075 -175)(1250 -175);
WIRE 16 -1 (1075 225)(1075 -175);
WIRE 16 -1 (875 225)(1075 225);
WIRE 16 -1 (2175 75)(2175 275);
WIRE 16 -1 (2175 275)(2300 275);
WIRE 16 -1 (2175 275)(2150 275);
WIRE 16 -1 (2150 425)(2150 275);
WIRE 16 -1 (2150 275)(875 275);
FORCEPROP 2 LAST SIG_NAME PWRGD_P3V3_AUX_PDB_BUF_R
J 0
(1065 285);
DISPLAY 0.851064 (1065 285);
PAINT WHITE (1065 285);
FORCEPROP 2 LASTPROP $XRERR UNIQUE?
J 0
(825 285);
DISPLAY 0.638298 (825 285);
PAINT MONO (825 285);
DISPLAY INVISIBLE (825 285);
WIRE 16 -1 (-1025 275)(225 275);
FORCEPROP 2 LAST SIG_NAME PWRGD_P3V3_AUX_PDB_R
J 0
(-685 285);
DISPLAY 0.851064 (-685 285);
PAINT WHITE (-685 285);
FORCEPROP 2 LASTPROP $XRERR UNIQUE?
J 0
(-925 285);
DISPLAY 0.638298 (-925 285);
PAINT MONO (-925 285);
DISPLAY INVISIBLE (-925 285);
WIRE 16 -1 (3625 275)(2500 275);
FORCEPROP 2 LAST SIG_NAME PWRGD_P3V3_AUX_PDB_BUF
J 0
(2690 285);
DISPLAY 0.808511 (2690 285);
PAINT WHITE (2690 285);
WIRE 16 -1 (3225 2075)(2100 2075);
FORCEPROP 2 LAST SIG_NAME FM_GPU_HSC_EN_BUF
J 0
(2290 2085);
DISPLAY 0.808511 (2290 2085);
PAINT WHITE (2290 2085);
WIRE 16 -1 (2275 -1475)(1975 -1475);
WIRE 16 -1 (1975 -1675)(1975 -1475);
WIRE 16 -1 (1975 -1475)(1200 -1475);
FORCEPROP 2 LAST SIG_NAME HPDB_HSC_PWRGD_ISO
J 0
(1265 -1465);
DISPLAY 0.808511 (1265 -1465);
WIRE 16 -1 (1200 -1400)(1200 -1475);
WIRE 16 -1 (1200 -1475)(1200 -1525);
DOT 1 (-1125 -2075);
DOT 1 (50 -1775);
DOT 1 (1725 2075);
DOT 1 (925 2675);
DOT 1 (1750 2075);
DOT 1 (2175 275);
DOT 1 (2150 275);
DOT 1 (1250 -175);
DOT 1 (-1100 -2075);
DOT 1 (1200 -1475);
DOT 1 (1975 -1475);
DOT 1 (-1775 2825);
DOT 1 (-1800 2825);
FORCENOTE
OUT PUT IS PUSH PULL MODE
(-625 1625) 0;
DISPLAY LEFT (-625 1625);
DISPLAY 1.595745 (-625 1625);
PAINT PINK (-625 1625);
QUIT
